-- pcdb file, Rev:1.0 written by Allegro Design Entry HDL 16.5-S008 (v16-5-13Y) 10/18/2011 on Tue Oct 25 13:21:17 2011
#ISCELL
  mstr_standard drawing *
  *
#ISCELL
  mstr_standard synonym *
  page1_4p
